(kicad_pcb
	(version 20260206)
	(generator "pcbnew")
	(generator_version "10.0")
	(general
		(thickness 1.6)
		(legacy_teardrops no)
	)
	(paper "A4")
	(title_block
		(title "Bryce Canyon_IOM_IOC_16318-2_OCP.brd")
		(comment 1 "Bryce Canyon / footprint 27 of 1605 (MEZZ1), pads 118-122 of 122")
	)
	(layers
		(0 "F.Cu" signal "TOP")
		(4 "In1.Cu" signal "L2GND")
		(6 "In2.Cu" signal "L3")
		(8 "In3.Cu" signal "L4VCC")
		(10 "In4.Cu" signal "L5VCC")
		(12 "In5.Cu" signal "L6")
		(14 "In6.Cu" signal "L7GND")
		(2 "B.Cu" signal "BOTTOM")
		(9 "F.Adhes" user "F.Adhesive")
		(11 "B.Adhes" user "B.Adhesive")
		(13 "F.Paste" user "Package Geometry/Pastemask Top")
		(15 "B.Paste" user "Package Geometry/Pastemask Bottom")
		(5 "F.SilkS" user "Ref Des/Silkscreen Top")
		(7 "B.SilkS" user "Ref Des/Silkscreen Bottom")
		(1 "F.Mask" user "Board Geometry/Soldermask Top")
		(3 "B.Mask" user "Board Geometry/Soldermask Bottom")
		(17 "Dwgs.User" user "User.Drawings")
		(19 "Cmts.User" user "User.Comments")
		(21 "Eco1.User" user "User.Eco1")
		(23 "Eco2.User" user "User.Eco2")
		(25 "Edge.Cuts" user "Board Geometry/Outline")
		(27 "Margin" user)
		(31 "F.CrtYd" user "Package Geometry/Place Bound Top")
		(29 "B.CrtYd" user "Package Geometry/Place Bound Bottom")
		(35 "F.Fab" user "Ref Des/Assembly Top")
		(33 "B.Fab" user "Ref Des/Assembly Bottom")
	)
	(footprint ""
		(layer "F.Cu")
		(at 77.700124 -72.55002 -90)
		(property "Reference" "MEZZ1"
			(at 0 0 270)
			(layer "F.SilkS")
			(hide yes)
			(effects
				(font
					(size 1.27 1.27)
				)
			)
		)
		(property "Value" "FCI-CONN120-GP-U1"
			(at -28.2321 -1.7018 270)
			(unlocked yes)
			(layer "F.Fab")
			(hide yes)
			(effects
				(font
					(size 1.016 1.016)
					(thickness 0.1524)
				)
			)
		)
		(property "Device Type" "61082-121402LF-U1"
			(at -28.2321 -3.2258 270)
			(unlocked yes)
			(layer "F.Fab")
			(hide yes)
			(effects
				(font
					(size 1.016 1.016)
					(thickness 0.1524)
				)
			)
		)
		(duplicate_pad_numbers_are_jumpers no)
		(pad "116" smd rect
			(at -20.40001 2.22504 270)
			(size 0.508 2.0574)
			(layers "F.Cu" "F.Mask" "F.Paste")
			(net "PCIE_COMP_TO_IOM_23_DP")
		)
		(pad "117" smd rect
			(at -21.20011 2.22504 270)
			(size 0.508 2.0574)
			(layers "F.Cu" "F.Mask" "F.Paste")
			(net "PCIE_COMP_TO_IOM_23_DN")
		)
		(pad "118" smd rect
			(at -21.999956 2.22504 270)
			(size 0.508 2.0574)
			(layers "F.Cu" "F.Mask" "F.Paste")
			(net "GND")
		)
		(pad "119" smd rect
			(at -22.800056 2.22504 270)
			(size 0.508 2.0574)
			(layers "F.Cu" "F.Mask" "F.Paste")
			(net "GND")
		)
		(pad "120" smd rect
			(at -23.599902 2.22504 270)
			(size 0.508 2.0574)
			(layers "F.Cu" "F.Mask" "F.Paste")
			(net "MEZZ_A_PRSNT_120_N")
		)
	)
)
